(kicad_pcb
	(version 20260206)
	(generator "pcbnew")
	(generator_version "10.0")
	(general
		(thickness 1.6)
		(legacy_teardrops no)
	)
	(paper "A4")
	(title_block
		(title "03242023_DA0F0TMBIJ0_F0T_Motherboard_J_brd_V01_OCP.brd")
		(comment 1 "Grand Teton / footprints 1973-1979 of 6105")
	)
	(layers
		(0 "F.Cu" signal "TOP")
		(4 "In1.Cu" signal "GND")
		(6 "In2.Cu" signal "IN1")
		(8 "In3.Cu" signal "GND1")
		(10 "In4.Cu" signal "IN2")
		(12 "In5.Cu" signal "GND2")
		(14 "In6.Cu" signal "IN3")
		(16 "In7.Cu" signal "GND3")
		(18 "In8.Cu" signal "VCC")
		(20 "In9.Cu" signal "VCC1")
		(22 "In10.Cu" signal "GND4")
		(24 "In11.Cu" signal "IN4")
		(26 "In12.Cu" signal "GND5")
		(28 "In13.Cu" signal "IN5")
		(30 "In14.Cu" signal "GND6")
		(32 "In15.Cu" signal "IN6")
		(34 "In16.Cu" signal "GND7")
		(2 "B.Cu" signal "BOTTOM")
		(9 "F.Adhes" user "F.Adhesive")
		(11 "B.Adhes" user "B.Adhesive")
		(13 "F.Paste" user "Package Geometry/Pastemask Top")
		(15 "B.Paste" user "Package Geometry/Pastemask Bottom")
		(5 "F.SilkS" user "Ref Des/Silkscreen Top")
		(7 "B.SilkS" user "Ref Des/Silkscreen Bottom")
		(1 "F.Mask" user "Board Geometry/Soldermask Top")
		(3 "B.Mask" user "Board Geometry/Soldermask Bottom")
		(17 "Dwgs.User" user "User.Drawings")
		(19 "Cmts.User" user "User.Comments")
		(21 "Eco1.User" user "User.Eco1")
		(23 "Eco2.User" user "User.Eco2")
		(25 "Edge.Cuts" user "Board Geometry/Outline")
		(27 "Margin" user)
		(31 "F.CrtYd" user "Package Geometry/Place Bound Top")
		(29 "B.CrtYd" user "Package Geometry/Place Bound Bottom")
		(35 "F.Fab" user "Ref Des/Assembly Top")
		(33 "B.Fab" user "Ref Des/Assembly Bottom")
	)
	(footprint ""
		(layer "F.Cu")
		(at 117.904514 -336.192368 90)
		(property "Reference" "PC523"
			(at 0 0 90)
			(layer "F.SilkS")
			(hide yes)
			(effects
				(font
					(size 1.27 1.27)
				)
			)
		)
		(property "Value" ""
			(at 0 0 90)
			(layer "F.Fab")
			(effects
				(font
					(size 1.27 1.27)
				)
			)
		)
		(duplicate_pad_numbers_are_jumpers no)
		(fp_line
			(start 0.7874 -0.4064)
			(end 0.7874 0.4064)
			(stroke
				(width 0.1524)
				(type default)
			)
			(layer "F.SilkS")
		)
		(fp_line
			(start -0.7874 -0.4064)
			(end 0.7874 -0.4064)
			(stroke
				(width 0.1524)
				(type default)
			)
			(layer "F.SilkS")
		)
		(fp_line
			(start 0.7874 0.4064)
			(end -0.7874 0.4064)
			(stroke
				(width 0.1524)
				(type default)
			)
			(layer "F.SilkS")
		)
		(fp_line
			(start -0.7874 0.4064)
			(end -0.7874 -0.4064)
			(stroke
				(width 0.1524)
				(type default)
			)
			(layer "F.SilkS")
		)
		(fp_line
			(start -0.12065 -0.305054)
			(end -0.12065 -0.2794)
			(stroke
				(width 0.1)
				(type default)
			)
			(layer "F.Fab")
		)
		(fp_line
			(start -0.67945 -0.305054)
			(end -0.12065 -0.305054)
			(stroke
				(width 0.1)
				(type default)
			)
			(layer "F.Fab")
		)
		(fp_line
			(start 0.67945 -0.3048)
			(end 0.67945 0.3048)
			(stroke
				(width 0.1)
				(type default)
			)
			(layer "F.Fab")
		)
		(fp_line
			(start 0.12065 -0.3048)
			(end 0.67945 -0.3048)
			(stroke
				(width 0.1)
				(type default)
			)
			(layer "F.Fab")
		)
		(fp_line
			(start 0.12065 -0.2794)
			(end 0.12065 -0.3048)
			(stroke
				(width 0.1)
				(type default)
			)
			(layer "F.Fab")
		)
		(fp_line
			(start -0.12065 -0.2794)
			(end 0.12065 -0.2794)
			(stroke
				(width 0.1)
				(type default)
			)
			(layer "F.Fab")
		)
		(fp_line
			(start 0.120396 0.2794)
			(end -0.12065 0.2794)
			(stroke
				(width 0.1)
				(type default)
			)
			(layer "F.Fab")
		)
		(fp_line
			(start -0.12065 0.2794)
			(end -0.12065 0.3048)
			(stroke
				(width 0.1)
				(type default)
			)
			(layer "F.Fab")
		)
		(fp_line
			(start 0.67945 0.3048)
			(end 0.120396 0.3048)
			(stroke
				(width 0.1)
				(type default)
			)
			(layer "F.Fab")
		)
		(fp_line
			(start 0.120396 0.3048)
			(end 0.120396 0.2794)
			(stroke
				(width 0.1)
				(type default)
			)
			(layer "F.Fab")
		)
		(fp_line
			(start -0.12065 0.3048)
			(end -0.67945 0.3048)
			(stroke
				(width 0.1)
				(type default)
			)
			(layer "F.Fab")
		)
		(fp_line
			(start -0.67945 0.3048)
			(end -0.67945 -0.305054)
			(stroke
				(width 0.1)
				(type default)
			)
			(layer "F.Fab")
		)
		(pad "1" smd circle
			(at -0.40005 0 90)
			(size 0 0)
			(layers "F.Cu" "F.Mask" "F.Paste")
			(net "PVCCIN_CPU1_VDD4")
		)
		(pad "2" smd circle
			(at 0.40005 0 90)
			(size 0 0)
			(layers "F.Cu" "F.Mask" "F.Paste")
			(net "GND")
		)
	)
	(footprint ""
		(layer "F.Cu")
		(at 180.528468 -47.139098 180)
		(property "Reference" "C1101"
			(at 0 0 180)
			(layer "F.SilkS")
			(hide yes)
			(effects
				(font
					(size 1.27 1.27)
				)
			)
		)
		(property "Value" ""
			(at 0 0 180)
			(layer "F.Fab")
			(effects
				(font
					(size 1.27 1.27)
				)
			)
		)
		(duplicate_pad_numbers_are_jumpers no)
		(fp_line
			(start 0.299974 0.150114)
			(end -0.299974 0.150114)
			(stroke
				(width 0.1)
				(type default)
			)
			(layer "F.Fab")
		)
		(fp_line
			(start 0.299974 -0.150114)
			(end 0.299974 0.150114)
			(stroke
				(width 0.1)
				(type default)
			)
			(layer "F.Fab")
		)
		(fp_line
			(start -0.299974 0.150114)
			(end -0.299974 -0.150114)
			(stroke
				(width 0.1)
				(type default)
			)
			(layer "F.Fab")
		)
		(fp_line
			(start -0.299974 -0.150114)
			(end 0.299974 -0.150114)
			(stroke
				(width 0.1)
				(type default)
			)
			(layer "F.Fab")
		)
		(pad "1" smd rect
			(at -0.2667 0 180)
			(size 0.3048 0.381)
			(layers "F.Cu" "F.Mask" "F.Paste")
			(net "P3E_PCH_M2_TX_DN<2>")
		)
		(pad "2" smd rect
			(at 0.2667 0 180)
			(size 0.3048 0.381)
			(layers "F.Cu" "F.Mask" "F.Paste")
			(net "P3E_PCH_M2_TX_C_DN<2>")
		)
		(zone
			(layer "In1.Cu")
			(hatch none 0.5)
			(connect_pads
				(clearance 0)
			)
			(min_thickness 0.25)
			(keepout
				(tracks not_allowed)
				(vias allowed)
				(pads allowed)
				(copperpour not_allowed)
				(footprints allowed)
			)
			(placement
				(enabled no)
				(sheetname "")
			)
			(fill
				(thermal_gap 0.5)
				(thermal_bridge_width 0.5)
				(island_removal_mode 0)
			)
			(polygon
				(pts
					(arc
						(start 180.388768 -47.380398)
						(mid 180.44265 -47.35808)
						(end 180.464968 -47.304198)
					)
					(arc
						(start 180.464968 -46.973998)
						(mid 180.44265 -46.920116)
						(end 180.388768 -46.897798)
					)
					(arc
						(start 180.134768 -46.897798)
						(mid 180.080886 -46.920116)
						(end 180.058568 -46.973998)
					)
					(arc
						(start 180.058568 -47.304198)
						(mid 180.080886 -47.35808)
						(end 180.134768 -47.380398)
					)
				)
			)
		)
		(zone
			(layer "In1.Cu")
			(hatch none 0.5)
			(connect_pads
				(clearance 0)
			)
			(min_thickness 0.25)
			(keepout
				(tracks not_allowed)
				(vias allowed)
				(pads allowed)
				(copperpour not_allowed)
				(footprints allowed)
			)
			(placement
				(enabled no)
				(sheetname "")
			)
			(fill
				(thermal_gap 0.5)
				(thermal_bridge_width 0.5)
				(island_removal_mode 0)
			)
			(polygon
				(pts
					(arc
						(start 180.922168 -47.380398)
						(mid 180.97605 -47.35808)
						(end 180.998368 -47.304198)
					)
					(arc
						(start 180.998368 -46.973998)
						(mid 180.97605 -46.920116)
						(end 180.922168 -46.897798)
					)
					(arc
						(start 180.668168 -46.897798)
						(mid 180.614286 -46.920116)
						(end 180.591968 -46.973998)
					)
					(arc
						(start 180.591968 -47.304198)
						(mid 180.614286 -47.35808)
						(end 180.668168 -47.380398)
					)
				)
			)
		)
	)
	(footprint ""
		(layer "F.Cu")
		(at 161.29 -126.365 -90)
		(property "Reference" "R4641"
			(at 0 0 270)
			(layer "F.SilkS")
			(hide yes)
			(effects
				(font
					(size 1.27 1.27)
				)
			)
		)
		(property "Value" ""
			(at 0 0 270)
			(layer "F.Fab")
			(effects
				(font
					(size 1.27 1.27)
				)
			)
		)
		(duplicate_pad_numbers_are_jumpers no)
		(fp_line
			(start -2.234946 0.9271)
			(end -2.234946 -0.9271)
			(stroke
				(width 0.1524)
				(type default)
			)
			(layer "F.SilkS")
		)
		(fp_line
			(start 2.234946 0.9271)
			(end -2.234946 0.9271)
			(stroke
				(width 0.1524)
				(type default)
			)
			(layer "F.SilkS")
		)
		(fp_line
			(start -2.234946 -0.9271)
			(end 2.234946 -0.9271)
			(stroke
				(width 0.1524)
				(type default)
			)
			(layer "F.SilkS")
		)
		(fp_line
			(start 2.234946 -0.9271)
			(end 2.234946 0.9271)
			(stroke
				(width 0.1524)
				(type default)
			)
			(layer "F.SilkS")
		)
		(fp_line
			(start -1.575054 0.824992)
			(end 1.575054 0.824992)
			(stroke
				(width 0.1)
				(type default)
			)
			(layer "F.Fab")
		)
		(fp_line
			(start 1.575054 0.824992)
			(end 1.575054 -0.824992)
			(stroke
				(width 0.1)
				(type default)
			)
			(layer "F.Fab")
		)
		(fp_line
			(start -1.575054 -0.824992)
			(end -1.575054 0.824992)
			(stroke
				(width 0.1)
				(type default)
			)
			(layer "F.Fab")
		)
		(fp_line
			(start 1.575054 -0.824992)
			(end -1.575054 -0.824992)
			(stroke
				(width 0.1)
				(type default)
			)
			(layer "F.Fab")
		)
		(pad "1" smd rect
			(at -1.599946 0 270)
			(size 1.016 1.6002)
			(layers "F.Cu" "F.Mask" "F.Paste")
			(net "P5V")
		)
		(pad "2" smd rect
			(at 1.599946 0 270)
			(size 1.016 1.6002)
			(layers "F.Cu" "F.Mask" "F.Paste")
			(net "VR_P5V_EN_D")
		)
	)
	(footprint ""
		(layer "F.Cu")
		(at 27.628596 -395.374876 180)
		(property "Reference" "R3280"
			(at 0 0 180)
			(layer "F.SilkS")
			(hide yes)
			(effects
				(font
					(size 1.27 1.27)
				)
			)
		)
		(property "Value" ""
			(at 0 0 180)
			(layer "F.Fab")
			(effects
				(font
					(size 1.27 1.27)
				)
			)
		)
		(duplicate_pad_numbers_are_jumpers no)
		(fp_line
			(start 0.7874 0.4064)
			(end -0.7874 0.4064)
			(stroke
				(width 0.1524)
				(type default)
			)
			(layer "F.SilkS")
		)
		(fp_line
			(start 0.7874 -0.4064)
			(end 0.7874 0.4064)
			(stroke
				(width 0.1524)
				(type default)
			)
			(layer "F.SilkS")
		)
		(fp_line
			(start -0.7874 0.4064)
			(end -0.7874 -0.4064)
			(stroke
				(width 0.1524)
				(type default)
			)
			(layer "F.SilkS")
		)
		(fp_line
			(start -0.7874 -0.4064)
			(end 0.7874 -0.4064)
			(stroke
				(width 0.1524)
				(type default)
			)
			(layer "F.SilkS")
		)
		(fp_line
			(start 0.67945 0.3048)
			(end 0.120396 0.3048)
			(stroke
				(width 0.1)
				(type default)
			)
			(layer "F.Fab")
		)
		(fp_line
			(start 0.67945 -0.3048)
			(end 0.67945 0.3048)
			(stroke
				(width 0.1)
				(type default)
			)
			(layer "F.Fab")
		)
		(fp_line
			(start 0.12065 -0.2794)
			(end 0.12065 -0.3048)
			(stroke
				(width 0.1)
				(type default)
			)
			(layer "F.Fab")
		)
		(fp_line
			(start 0.12065 -0.3048)
			(end 0.67945 -0.3048)
			(stroke
				(width 0.1)
				(type default)
			)
			(layer "F.Fab")
		)
		(fp_line
			(start 0.120396 0.3048)
			(end 0.120396 0.2794)
			(stroke
				(width 0.1)
				(type default)
			)
			(layer "F.Fab")
		)
		(fp_line
			(start 0.120396 0.2794)
			(end -0.12065 0.2794)
			(stroke
				(width 0.1)
				(type default)
			)
			(layer "F.Fab")
		)
		(fp_line
			(start -0.12065 0.3048)
			(end -0.67945 0.3048)
			(stroke
				(width 0.1)
				(type default)
			)
			(layer "F.Fab")
		)
		(fp_line
			(start -0.12065 0.2794)
			(end -0.12065 0.3048)
			(stroke
				(width 0.1)
				(type default)
			)
			(layer "F.Fab")
		)
		(fp_line
			(start -0.12065 -0.2794)
			(end 0.12065 -0.2794)
			(stroke
				(width 0.1)
				(type default)
			)
			(layer "F.Fab")
		)
		(fp_line
			(start -0.12065 -0.305054)
			(end -0.12065 -0.2794)
			(stroke
				(width 0.1)
				(type default)
			)
			(layer "F.Fab")
		)
		(fp_line
			(start -0.67945 0.3048)
			(end -0.67945 -0.305054)
			(stroke
				(width 0.1)
				(type default)
			)
			(layer "F.Fab")
		)
		(fp_line
			(start -0.67945 -0.305054)
			(end -0.12065 -0.305054)
			(stroke
				(width 0.1)
				(type default)
			)
			(layer "F.Fab")
		)
		(pad "1" smd circle
			(at -0.40005 0 180)
			(size 0 0)
			(layers "F.Cu" "F.Mask" "F.Paste")
			(net "P3V3_AUX")
		)
		(pad "2" smd circle
			(at 0.40005 0 180)
			(size 0 0)
			(layers "F.Cu" "F.Mask" "F.Paste")
			(net "FM_P2E_EQB1")
		)
	)
	(footprint ""
		(layer "F.Cu")
		(at 432.757072 -177.903124 -90)
		(property "Reference" "PR1"
			(at 0 0 270)
			(layer "F.SilkS")
			(hide yes)
			(effects
				(font
					(size 1.27 1.27)
				)
			)
		)
		(property "Value" ""
			(at 0 0 270)
			(layer "F.Fab")
			(effects
				(font
					(size 1.27 1.27)
				)
			)
		)
		(duplicate_pad_numbers_are_jumpers no)
		(fp_line
			(start -0.7874 0.4064)
			(end -0.7874 -0.4064)
			(stroke
				(width 0.1524)
				(type default)
			)
			(layer "F.SilkS")
		)
		(fp_line
			(start 0.7874 0.4064)
			(end -0.7874 0.4064)
			(stroke
				(width 0.1524)
				(type default)
			)
			(layer "F.SilkS")
		)
		(fp_line
			(start -0.7874 -0.4064)
			(end 0.7874 -0.4064)
			(stroke
				(width 0.1524)
				(type default)
			)
			(layer "F.SilkS")
		)
		(fp_line
			(start 0.7874 -0.4064)
			(end 0.7874 0.4064)
			(stroke
				(width 0.1524)
				(type default)
			)
			(layer "F.SilkS")
		)
		(fp_line
			(start -0.67945 0.3048)
			(end -0.67945 -0.305054)
			(stroke
				(width 0.1)
				(type default)
			)
			(layer "F.Fab")
		)
		(fp_line
			(start -0.12065 0.3048)
			(end -0.67945 0.3048)
			(stroke
				(width 0.1)
				(type default)
			)
			(layer "F.Fab")
		)
		(fp_line
			(start 0.120396 0.3048)
			(end 0.120396 0.2794)
			(stroke
				(width 0.1)
				(type default)
			)
			(layer "F.Fab")
		)
		(fp_line
			(start 0.67945 0.3048)
			(end 0.120396 0.3048)
			(stroke
				(width 0.1)
				(type default)
			)
			(layer "F.Fab")
		)
		(fp_line
			(start -0.12065 0.2794)
			(end -0.12065 0.3048)
			(stroke
				(width 0.1)
				(type default)
			)
			(layer "F.Fab")
		)
		(fp_line
			(start 0.120396 0.2794)
			(end -0.12065 0.2794)
			(stroke
				(width 0.1)
				(type default)
			)
			(layer "F.Fab")
		)
		(fp_line
			(start -0.12065 -0.2794)
			(end 0.12065 -0.2794)
			(stroke
				(width 0.1)
				(type default)
			)
			(layer "F.Fab")
		)
		(fp_line
			(start 0.12065 -0.2794)
			(end 0.12065 -0.3048)
			(stroke
				(width 0.1)
				(type default)
			)
			(layer "F.Fab")
		)
		(fp_line
			(start 0.12065 -0.3048)
			(end 0.67945 -0.3048)
			(stroke
				(width 0.1)
				(type default)
			)
			(layer "F.Fab")
		)
		(fp_line
			(start 0.67945 -0.3048)
			(end 0.67945 0.3048)
			(stroke
				(width 0.1)
				(type default)
			)
			(layer "F.Fab")
		)
		(fp_line
			(start -0.67945 -0.305054)
			(end -0.12065 -0.305054)
			(stroke
				(width 0.1)
				(type default)
			)
			(layer "F.Fab")
		)
		(fp_line
			(start -0.12065 -0.305054)
			(end -0.12065 -0.2794)
			(stroke
				(width 0.1)
				(type default)
			)
			(layer "F.Fab")
		)
		(pad "1" smd circle
			(at -0.40005 0 270)
			(size 0 0)
			(layers "F.Cu" "F.Mask" "F.Paste")
			(net "GND")
		)
		(pad "2" smd circle
			(at 0.40005 0 270)
			(size 0 0)
			(layers "F.Cu" "F.Mask" "F.Paste")
			(net "GND")
		)
	)
	(footprint ""
		(layer "F.Cu")
		(at 249.034046 -540.634682 -90)
		(property "Reference" "ME27"
			(at 0.0254 -3.851148 270)
			(unlocked yes)
			(layer "F.SilkS")
			(effects
				(font
					(size 0.7874 0.5842)
					(thickness 0.1524)
				)
				(justify left)
			)
		)
		(property "Value" ""
			(at 0 0 270)
			(layer "F.Fab")
			(effects
				(font
					(size 1.27 1.27)
				)
			)
		)
		(duplicate_pad_numbers_are_jumpers no)
		(zone
			(layer "F.Cu")
			(hatch none 0.5)
			(connect_pads
				(clearance 0)
			)
			(min_thickness 0.25)
			(keepout
				(tracks allowed)
				(vias allowed)
				(pads allowed)
				(copperpour allowed)
				(footprints not_allowed)
			)
			(placement
				(enabled no)
				(sheetname "")
			)
			(fill
				(thermal_gap 0.5)
				(thermal_bridge_width 0.5)
				(island_removal_mode 0)
			)
			(polygon
				(pts
					(xy 249.034046 -540.634682) (xy 249.034046 18.165318) (xy 252.03404 18.165318) (xy 252.03404 -540.634682)
				)
			)
		)
	)
	(footprint ""
		(layer "F.Cu")
		(at 198.41464 -71.582788)
		(property "Reference" "PC2201"
			(at 0 0 0)
			(layer "F.SilkS")
			(hide yes)
			(effects
				(font
					(size 1.27 1.27)
				)
			)
		)
		(property "Value" ""
			(at 0 0 0)
			(layer "F.Fab")
			(effects
				(font
					(size 1.27 1.27)
				)
			)
		)
		(duplicate_pad_numbers_are_jumpers no)
		(fp_line
			(start -0.7874 -0.4064)
			(end 0.7874 -0.4064)
			(stroke
				(width 0.1524)
				(type default)
			)
			(layer "F.SilkS")
		)
		(fp_line
			(start -0.7874 0.4064)
			(end -0.7874 -0.4064)
			(stroke
				(width 0.1524)
				(type default)
			)
			(layer "F.SilkS")
		)
		(fp_line
			(start 0.7874 -0.4064)
			(end 0.7874 0.4064)
			(stroke
				(width 0.1524)
				(type default)
			)
			(layer "F.SilkS")
		)
		(fp_line
			(start 0.7874 0.4064)
			(end -0.7874 0.4064)
			(stroke
				(width 0.1524)
				(type default)
			)
			(layer "F.SilkS")
		)
		(fp_line
			(start -0.67945 -0.305054)
			(end -0.12065 -0.305054)
			(stroke
				(width 0.1)
				(type default)
			)
			(layer "F.Fab")
		)
		(fp_line
			(start -0.67945 0.3048)
			(end -0.67945 -0.305054)
			(stroke
				(width 0.1)
				(type default)
			)
			(layer "F.Fab")
		)
		(fp_line
			(start -0.12065 -0.305054)
			(end -0.12065 -0.2794)
			(stroke
				(width 0.1)
				(type default)
			)
			(layer "F.Fab")
		)
		(fp_line
			(start -0.12065 -0.2794)
			(end 0.12065 -0.2794)
			(stroke
				(width 0.1)
				(type default)
			)
			(layer "F.Fab")
		)
		(fp_line
			(start -0.12065 0.2794)
			(end -0.12065 0.3048)
			(stroke
				(width 0.1)
				(type default)
			)
			(layer "F.Fab")
		)
		(fp_line
			(start -0.12065 0.3048)
			(end -0.67945 0.3048)
			(stroke
				(width 0.1)
				(type default)
			)
			(layer "F.Fab")
		)
		(fp_line
			(start 0.120396 0.2794)
			(end -0.12065 0.2794)
			(stroke
				(width 0.1)
				(type default)
			)
			(layer "F.Fab")
		)
		(fp_line
			(start 0.120396 0.3048)
			(end 0.120396 0.2794)
			(stroke
				(width 0.1)
				(type default)
			)
			(layer "F.Fab")
		)
		(fp_line
			(start 0.12065 -0.3048)
			(end 0.67945 -0.3048)
			(stroke
				(width 0.1)
				(type default)
			)
			(layer "F.Fab")
		)
		(fp_line
			(start 0.12065 -0.2794)
			(end 0.12065 -0.3048)
			(stroke
				(width 0.1)
				(type default)
			)
			(layer "F.Fab")
		)
		(fp_line
			(start 0.67945 -0.3048)
			(end 0.67945 0.3048)
			(stroke
				(width 0.1)
				(type default)
			)
			(layer "F.Fab")
		)
		(fp_line
			(start 0.67945 0.3048)
			(end 0.120396 0.3048)
			(stroke
				(width 0.1)
				(type default)
			)
			(layer "F.Fab")
		)
		(pad "1" smd circle
			(at -0.40005 0)
			(size 0 0)
			(layers "F.Cu" "F.Mask" "F.Paste")
			(net "P3V3_E1S_DVDT_0")
		)
		(pad "2" smd circle
			(at 0.40005 0)
			(size 0 0)
			(layers "F.Cu" "F.Mask" "F.Paste")
			(net "GND")
		)
	)
)
